(kicad_pcb
	(version 20260206)
	(generator "pcbnew")
	(generator_version "10.0")
	(general
		(thickness 1.6)
		(legacy_teardrops no)
	)
	(paper "A4")
	(title_block
		(title "03242023_DA0F0TMBIJ0_F0T_Motherboard_J_brd_V01_OCP.brd")
		(comment 1 "Grand Teton / footprints 462-468 of 6105")
	)
	(layers
		(0 "F.Cu" signal "TOP")
		(4 "In1.Cu" signal "GND")
		(6 "In2.Cu" signal "IN1")
		(8 "In3.Cu" signal "GND1")
		(10 "In4.Cu" signal "IN2")
		(12 "In5.Cu" signal "GND2")
		(14 "In6.Cu" signal "IN3")
		(16 "In7.Cu" signal "GND3")
		(18 "In8.Cu" signal "VCC")
		(20 "In9.Cu" signal "VCC1")
		(22 "In10.Cu" signal "GND4")
		(24 "In11.Cu" signal "IN4")
		(26 "In12.Cu" signal "GND5")
		(28 "In13.Cu" signal "IN5")
		(30 "In14.Cu" signal "GND6")
		(32 "In15.Cu" signal "IN6")
		(34 "In16.Cu" signal "GND7")
		(2 "B.Cu" signal "BOTTOM")
		(9 "F.Adhes" user "F.Adhesive")
		(11 "B.Adhes" user "B.Adhesive")
		(13 "F.Paste" user "Package Geometry/Pastemask Top")
		(15 "B.Paste" user "Package Geometry/Pastemask Bottom")
		(5 "F.SilkS" user "Ref Des/Silkscreen Top")
		(7 "B.SilkS" user "Ref Des/Silkscreen Bottom")
		(1 "F.Mask" user "Board Geometry/Soldermask Top")
		(3 "B.Mask" user "Board Geometry/Soldermask Bottom")
		(17 "Dwgs.User" user "User.Drawings")
		(19 "Cmts.User" user "User.Comments")
		(21 "Eco1.User" user "User.Eco1")
		(23 "Eco2.User" user "User.Eco2")
		(25 "Edge.Cuts" user "Board Geometry/Outline")
		(27 "Margin" user)
		(31 "F.CrtYd" user "Package Geometry/Place Bound Top")
		(29 "B.CrtYd" user "Package Geometry/Place Bound Bottom")
		(35 "F.Fab" user "Ref Des/Assembly Top")
		(33 "B.Fab" user "Ref Des/Assembly Bottom")
	)
	(footprint ""
		(layer "F.Cu")
		(at 413.48025 -408.517344 -90)
		(property "Reference" "C897"
			(at 0 0 270)
			(layer "F.SilkS")
			(hide yes)
			(effects
				(font
					(size 1.27 1.27)
				)
			)
		)
		(property "Value" ""
			(at 0 0 270)
			(layer "F.Fab")
			(effects
				(font
					(size 1.27 1.27)
				)
			)
		)
		(duplicate_pad_numbers_are_jumpers no)
		(fp_line
			(start -0.299974 0.150114)
			(end -0.299974 -0.150114)
			(stroke
				(width 0.1)
				(type default)
			)
			(layer "F.Fab")
		)
		(fp_line
			(start 0.299974 0.150114)
			(end -0.299974 0.150114)
			(stroke
				(width 0.1)
				(type default)
			)
			(layer "F.Fab")
		)
		(fp_line
			(start -0.299974 -0.150114)
			(end 0.299974 -0.150114)
			(stroke
				(width 0.1)
				(type default)
			)
			(layer "F.Fab")
		)
		(fp_line
			(start 0.299974 -0.150114)
			(end 0.299974 0.150114)
			(stroke
				(width 0.1)
				(type default)
			)
			(layer "F.Fab")
		)
		(pad "1" smd rect
			(at -0.2667 0 270)
			(size 0.3048 0.381)
			(layers "F.Cu" "F.Mask" "F.Paste")
			(net "P5E_CPU0_PE3_TX_C_DP<2>")
		)
		(pad "2" smd rect
			(at 0.2667 0 270)
			(size 0.3048 0.381)
			(layers "F.Cu" "F.Mask" "F.Paste")
			(net "P5E_CPU0_PE3_TX_DP<2>")
		)
	)
	(footprint ""
		(layer "F.Cu")
		(at 135.56488 -100.167948 -90)
		(property "Reference" "R4414"
			(at 0 0 270)
			(layer "F.SilkS")
			(hide yes)
			(effects
				(font
					(size 1.27 1.27)
				)
			)
		)
		(property "Value" ""
			(at 0 0 270)
			(layer "F.Fab")
			(effects
				(font
					(size 1.27 1.27)
				)
			)
		)
		(duplicate_pad_numbers_are_jumpers no)
		(fp_line
			(start -0.7874 0.4064)
			(end -0.7874 -0.4064)
			(stroke
				(width 0.1524)
				(type default)
			)
			(layer "F.SilkS")
		)
		(fp_line
			(start 0.7874 0.4064)
			(end -0.7874 0.4064)
			(stroke
				(width 0.1524)
				(type default)
			)
			(layer "F.SilkS")
		)
		(fp_line
			(start -0.7874 -0.4064)
			(end 0.7874 -0.4064)
			(stroke
				(width 0.1524)
				(type default)
			)
			(layer "F.SilkS")
		)
		(fp_line
			(start 0.7874 -0.4064)
			(end 0.7874 0.4064)
			(stroke
				(width 0.1524)
				(type default)
			)
			(layer "F.SilkS")
		)
		(fp_line
			(start -0.67945 0.3048)
			(end -0.67945 -0.305054)
			(stroke
				(width 0.1)
				(type default)
			)
			(layer "F.Fab")
		)
		(fp_line
			(start -0.12065 0.3048)
			(end -0.67945 0.3048)
			(stroke
				(width 0.1)
				(type default)
			)
			(layer "F.Fab")
		)
		(fp_line
			(start 0.120396 0.3048)
			(end 0.120396 0.2794)
			(stroke
				(width 0.1)
				(type default)
			)
			(layer "F.Fab")
		)
		(fp_line
			(start 0.67945 0.3048)
			(end 0.120396 0.3048)
			(stroke
				(width 0.1)
				(type default)
			)
			(layer "F.Fab")
		)
		(fp_line
			(start -0.12065 0.2794)
			(end -0.12065 0.3048)
			(stroke
				(width 0.1)
				(type default)
			)
			(layer "F.Fab")
		)
		(fp_line
			(start 0.120396 0.2794)
			(end -0.12065 0.2794)
			(stroke
				(width 0.1)
				(type default)
			)
			(layer "F.Fab")
		)
		(fp_line
			(start -0.12065 -0.2794)
			(end 0.12065 -0.2794)
			(stroke
				(width 0.1)
				(type default)
			)
			(layer "F.Fab")
		)
		(fp_line
			(start 0.12065 -0.2794)
			(end 0.12065 -0.3048)
			(stroke
				(width 0.1)
				(type default)
			)
			(layer "F.Fab")
		)
		(fp_line
			(start 0.12065 -0.3048)
			(end 0.67945 -0.3048)
			(stroke
				(width 0.1)
				(type default)
			)
			(layer "F.Fab")
		)
		(fp_line
			(start 0.67945 -0.3048)
			(end 0.67945 0.3048)
			(stroke
				(width 0.1)
				(type default)
			)
			(layer "F.Fab")
		)
		(fp_line
			(start -0.67945 -0.305054)
			(end -0.12065 -0.305054)
			(stroke
				(width 0.1)
				(type default)
			)
			(layer "F.Fab")
		)
		(fp_line
			(start -0.12065 -0.305054)
			(end -0.12065 -0.2794)
			(stroke
				(width 0.1)
				(type default)
			)
			(layer "F.Fab")
		)
		(pad "1" smd circle
			(at -0.40005 0 270)
			(size 0 0)
			(layers "F.Cu" "F.Mask" "F.Paste")
			(net "H_CPU1_MEMTRIP_VT_N")
		)
		(pad "2" smd circle
			(at 0.40005 0 270)
			(size 0 0)
			(layers "F.Cu" "F.Mask" "F.Paste")
			(net "H_CPU1_MEMTRIP_LVC1_N")
		)
	)
	(footprint ""
		(layer "F.Cu")
		(at 431.47488 -128.361948 90)
		(property "Reference" "PR4231"
			(at 0 0 90)
			(layer "F.SilkS")
			(hide yes)
			(effects
				(font
					(size 1.27 1.27)
				)
			)
		)
		(property "Value" ""
			(at 0 0 90)
			(layer "F.Fab")
			(effects
				(font
					(size 1.27 1.27)
				)
			)
		)
		(duplicate_pad_numbers_are_jumpers no)
		(fp_line
			(start 0.7874 -0.4064)
			(end 0.7874 0.4064)
			(stroke
				(width 0.1524)
				(type default)
			)
			(layer "F.SilkS")
		)
		(fp_line
			(start -0.7874 -0.4064)
			(end 0.7874 -0.4064)
			(stroke
				(width 0.1524)
				(type default)
			)
			(layer "F.SilkS")
		)
		(fp_line
			(start 0.7874 0.4064)
			(end -0.7874 0.4064)
			(stroke
				(width 0.1524)
				(type default)
			)
			(layer "F.SilkS")
		)
		(fp_line
			(start -0.7874 0.4064)
			(end -0.7874 -0.4064)
			(stroke
				(width 0.1524)
				(type default)
			)
			(layer "F.SilkS")
		)
		(fp_line
			(start -0.12065 -0.305054)
			(end -0.12065 -0.2794)
			(stroke
				(width 0.1)
				(type default)
			)
			(layer "F.Fab")
		)
		(fp_line
			(start -0.67945 -0.305054)
			(end -0.12065 -0.305054)
			(stroke
				(width 0.1)
				(type default)
			)
			(layer "F.Fab")
		)
		(fp_line
			(start 0.67945 -0.3048)
			(end 0.67945 0.3048)
			(stroke
				(width 0.1)
				(type default)
			)
			(layer "F.Fab")
		)
		(fp_line
			(start 0.12065 -0.3048)
			(end 0.67945 -0.3048)
			(stroke
				(width 0.1)
				(type default)
			)
			(layer "F.Fab")
		)
		(fp_line
			(start 0.12065 -0.2794)
			(end 0.12065 -0.3048)
			(stroke
				(width 0.1)
				(type default)
			)
			(layer "F.Fab")
		)
		(fp_line
			(start -0.12065 -0.2794)
			(end 0.12065 -0.2794)
			(stroke
				(width 0.1)
				(type default)
			)
			(layer "F.Fab")
		)
		(fp_line
			(start 0.120396 0.2794)
			(end -0.12065 0.2794)
			(stroke
				(width 0.1)
				(type default)
			)
			(layer "F.Fab")
		)
		(fp_line
			(start -0.12065 0.2794)
			(end -0.12065 0.3048)
			(stroke
				(width 0.1)
				(type default)
			)
			(layer "F.Fab")
		)
		(fp_line
			(start 0.67945 0.3048)
			(end 0.120396 0.3048)
			(stroke
				(width 0.1)
				(type default)
			)
			(layer "F.Fab")
		)
		(fp_line
			(start 0.120396 0.3048)
			(end 0.120396 0.2794)
			(stroke
				(width 0.1)
				(type default)
			)
			(layer "F.Fab")
		)
		(fp_line
			(start -0.12065 0.3048)
			(end -0.67945 0.3048)
			(stroke
				(width 0.1)
				(type default)
			)
			(layer "F.Fab")
		)
		(fp_line
			(start -0.67945 0.3048)
			(end -0.67945 -0.305054)
			(stroke
				(width 0.1)
				(type default)
			)
			(layer "F.Fab")
		)
		(pad "1" smd circle
			(at -0.40005 0 90)
			(size 0 0)
			(layers "F.Cu" "F.Mask" "F.Paste")
			(net "NC_PVCCD_HV_CPU0_ACSP3")
		)
		(pad "2" smd circle
			(at 0.40005 0 90)
			(size 0 0)
			(layers "F.Cu" "F.Mask" "F.Paste")
			(net "GND")
		)
	)
	(footprint ""
		(layer "F.Cu")
		(at 46.178724 -353.61626 -90)
		(property "Reference" "PC1194_P1_4"
			(at 0 0 270)
			(layer "F.SilkS")
			(hide yes)
			(effects
				(font
					(size 1.27 1.27)
				)
			)
		)
		(property "Value" ""
			(at 0 0 270)
			(layer "F.Fab")
			(effects
				(font
					(size 1.27 1.27)
				)
			)
		)
		(duplicate_pad_numbers_are_jumpers no)
		(fp_line
			(start -0.7874 0.4064)
			(end -0.7874 -0.4064)
			(stroke
				(width 0.1524)
				(type default)
			)
			(layer "F.SilkS")
		)
		(fp_line
			(start 0.7874 0.4064)
			(end -0.7874 0.4064)
			(stroke
				(width 0.1524)
				(type default)
			)
			(layer "F.SilkS")
		)
		(fp_line
			(start -0.7874 -0.4064)
			(end 0.7874 -0.4064)
			(stroke
				(width 0.1524)
				(type default)
			)
			(layer "F.SilkS")
		)
		(fp_line
			(start 0.7874 -0.4064)
			(end 0.7874 0.4064)
			(stroke
				(width 0.1524)
				(type default)
			)
			(layer "F.SilkS")
		)
		(fp_line
			(start -0.67945 0.3048)
			(end -0.67945 -0.305054)
			(stroke
				(width 0.1)
				(type default)
			)
			(layer "F.Fab")
		)
		(fp_line
			(start -0.12065 0.3048)
			(end -0.67945 0.3048)
			(stroke
				(width 0.1)
				(type default)
			)
			(layer "F.Fab")
		)
		(fp_line
			(start 0.120396 0.3048)
			(end 0.120396 0.2794)
			(stroke
				(width 0.1)
				(type default)
			)
			(layer "F.Fab")
		)
		(fp_line
			(start 0.67945 0.3048)
			(end 0.120396 0.3048)
			(stroke
				(width 0.1)
				(type default)
			)
			(layer "F.Fab")
		)
		(fp_line
			(start -0.12065 0.2794)
			(end -0.12065 0.3048)
			(stroke
				(width 0.1)
				(type default)
			)
			(layer "F.Fab")
		)
		(fp_line
			(start 0.120396 0.2794)
			(end -0.12065 0.2794)
			(stroke
				(width 0.1)
				(type default)
			)
			(layer "F.Fab")
		)
		(fp_line
			(start -0.12065 -0.2794)
			(end 0.12065 -0.2794)
			(stroke
				(width 0.1)
				(type default)
			)
			(layer "F.Fab")
		)
		(fp_line
			(start 0.12065 -0.2794)
			(end 0.12065 -0.3048)
			(stroke
				(width 0.1)
				(type default)
			)
			(layer "F.Fab")
		)
		(fp_line
			(start 0.12065 -0.3048)
			(end 0.67945 -0.3048)
			(stroke
				(width 0.1)
				(type default)
			)
			(layer "F.Fab")
		)
		(fp_line
			(start 0.67945 -0.3048)
			(end 0.67945 0.3048)
			(stroke
				(width 0.1)
				(type default)
			)
			(layer "F.Fab")
		)
		(fp_line
			(start -0.67945 -0.305054)
			(end -0.12065 -0.305054)
			(stroke
				(width 0.1)
				(type default)
			)
			(layer "F.Fab")
		)
		(fp_line
			(start -0.12065 -0.305054)
			(end -0.12065 -0.2794)
			(stroke
				(width 0.1)
				(type default)
			)
			(layer "F.Fab")
		)
		(pad "1" smd circle
			(at -0.40005 0 270)
			(size 0 0)
			(layers "F.Cu" "F.Mask" "F.Paste")
			(net "SW_P12V_PVCCFA_EHV_FIVRA_CPU1_L")
		)
		(pad "2" smd circle
			(at 0.40005 0 270)
			(size 0 0)
			(layers "F.Cu" "F.Mask" "F.Paste")
			(net "GND")
		)
	)
	(footprint ""
		(layer "F.Cu")
		(at 186.8932 -93.91015 90)
		(property "Reference" "R4751"
			(at 0 0 90)
			(layer "F.SilkS")
			(hide yes)
			(effects
				(font
					(size 1.27 1.27)
				)
			)
		)
		(property "Value" ""
			(at 0 0 90)
			(layer "F.Fab")
			(effects
				(font
					(size 1.27 1.27)
				)
			)
		)
		(duplicate_pad_numbers_are_jumpers no)
		(fp_line
			(start 0.7874 -0.4064)
			(end 0.7874 0.4064)
			(stroke
				(width 0.1524)
				(type default)
			)
			(layer "F.SilkS")
		)
		(fp_line
			(start -0.7874 -0.4064)
			(end 0.7874 -0.4064)
			(stroke
				(width 0.1524)
				(type default)
			)
			(layer "F.SilkS")
		)
		(fp_line
			(start 0.7874 0.4064)
			(end -0.7874 0.4064)
			(stroke
				(width 0.1524)
				(type default)
			)
			(layer "F.SilkS")
		)
		(fp_line
			(start -0.7874 0.4064)
			(end -0.7874 -0.4064)
			(stroke
				(width 0.1524)
				(type default)
			)
			(layer "F.SilkS")
		)
		(fp_line
			(start -0.12065 -0.305054)
			(end -0.12065 -0.2794)
			(stroke
				(width 0.1)
				(type default)
			)
			(layer "F.Fab")
		)
		(fp_line
			(start -0.67945 -0.305054)
			(end -0.12065 -0.305054)
			(stroke
				(width 0.1)
				(type default)
			)
			(layer "F.Fab")
		)
		(fp_line
			(start 0.67945 -0.3048)
			(end 0.67945 0.3048)
			(stroke
				(width 0.1)
				(type default)
			)
			(layer "F.Fab")
		)
		(fp_line
			(start 0.12065 -0.3048)
			(end 0.67945 -0.3048)
			(stroke
				(width 0.1)
				(type default)
			)
			(layer "F.Fab")
		)
		(fp_line
			(start 0.12065 -0.2794)
			(end 0.12065 -0.3048)
			(stroke
				(width 0.1)
				(type default)
			)
			(layer "F.Fab")
		)
		(fp_line
			(start -0.12065 -0.2794)
			(end 0.12065 -0.2794)
			(stroke
				(width 0.1)
				(type default)
			)
			(layer "F.Fab")
		)
		(fp_line
			(start 0.120396 0.2794)
			(end -0.12065 0.2794)
			(stroke
				(width 0.1)
				(type default)
			)
			(layer "F.Fab")
		)
		(fp_line
			(start -0.12065 0.2794)
			(end -0.12065 0.3048)
			(stroke
				(width 0.1)
				(type default)
			)
			(layer "F.Fab")
		)
		(fp_line
			(start 0.67945 0.3048)
			(end 0.120396 0.3048)
			(stroke
				(width 0.1)
				(type default)
			)
			(layer "F.Fab")
		)
		(fp_line
			(start 0.120396 0.3048)
			(end 0.120396 0.2794)
			(stroke
				(width 0.1)
				(type default)
			)
			(layer "F.Fab")
		)
		(fp_line
			(start -0.12065 0.3048)
			(end -0.67945 0.3048)
			(stroke
				(width 0.1)
				(type default)
			)
			(layer "F.Fab")
		)
		(fp_line
			(start -0.67945 0.3048)
			(end -0.67945 -0.305054)
			(stroke
				(width 0.1)
				(type default)
			)
			(layer "F.Fab")
		)
		(pad "1" smd circle
			(at -0.40005 0 90)
			(size 0 0)
			(layers "F.Cu" "F.Mask" "F.Paste")
			(net "HP_LVC3_OCP_V3_1_PWRGD_R")
		)
		(pad "2" smd circle
			(at 0.40005 0 90)
			(size 0 0)
			(layers "F.Cu" "F.Mask" "F.Paste")
			(net "HP_LVC3_OCP_V3_1_FUSE_PWRGD")
		)
	)
	(footprint ""
		(layer "F.Cu")
		(at 364.50143 -245.634002 -90)
		(property "Reference" "C997"
			(at 0 0 270)
			(layer "F.SilkS")
			(hide yes)
			(effects
				(font
					(size 1.27 1.27)
				)
			)
		)
		(property "Value" ""
			(at 0 0 270)
			(layer "F.Fab")
			(effects
				(font
					(size 1.27 1.27)
				)
			)
		)
		(duplicate_pad_numbers_are_jumpers no)
		(fp_line
			(start -0.7874 0.4064)
			(end -0.7874 -0.4064)
			(stroke
				(width 0.1524)
				(type default)
			)
			(layer "F.SilkS")
		)
		(fp_line
			(start 0.7874 0.4064)
			(end -0.7874 0.4064)
			(stroke
				(width 0.1524)
				(type default)
			)
			(layer "F.SilkS")
		)
		(fp_line
			(start -0.7874 -0.4064)
			(end 0.7874 -0.4064)
			(stroke
				(width 0.1524)
				(type default)
			)
			(layer "F.SilkS")
		)
		(fp_line
			(start 0.7874 -0.4064)
			(end 0.7874 0.4064)
			(stroke
				(width 0.1524)
				(type default)
			)
			(layer "F.SilkS")
		)
		(fp_line
			(start -0.67945 0.3048)
			(end -0.67945 -0.305054)
			(stroke
				(width 0.1)
				(type default)
			)
			(layer "F.Fab")
		)
		(fp_line
			(start -0.12065 0.3048)
			(end -0.67945 0.3048)
			(stroke
				(width 0.1)
				(type default)
			)
			(layer "F.Fab")
		)
		(fp_line
			(start 0.120396 0.3048)
			(end 0.120396 0.2794)
			(stroke
				(width 0.1)
				(type default)
			)
			(layer "F.Fab")
		)
		(fp_line
			(start 0.67945 0.3048)
			(end 0.120396 0.3048)
			(stroke
				(width 0.1)
				(type default)
			)
			(layer "F.Fab")
		)
		(fp_line
			(start -0.12065 0.2794)
			(end -0.12065 0.3048)
			(stroke
				(width 0.1)
				(type default)
			)
			(layer "F.Fab")
		)
		(fp_line
			(start 0.120396 0.2794)
			(end -0.12065 0.2794)
			(stroke
				(width 0.1)
				(type default)
			)
			(layer "F.Fab")
		)
		(fp_line
			(start -0.12065 -0.2794)
			(end 0.12065 -0.2794)
			(stroke
				(width 0.1)
				(type default)
			)
			(layer "F.Fab")
		)
		(fp_line
			(start 0.12065 -0.2794)
			(end 0.12065 -0.3048)
			(stroke
				(width 0.1)
				(type default)
			)
			(layer "F.Fab")
		)
		(fp_line
			(start 0.12065 -0.3048)
			(end 0.67945 -0.3048)
			(stroke
				(width 0.1)
				(type default)
			)
			(layer "F.Fab")
		)
		(fp_line
			(start 0.67945 -0.3048)
			(end 0.67945 0.3048)
			(stroke
				(width 0.1)
				(type default)
			)
			(layer "F.Fab")
		)
		(fp_line
			(start -0.67945 -0.305054)
			(end -0.12065 -0.305054)
			(stroke
				(width 0.1)
				(type default)
			)
			(layer "F.Fab")
		)
		(fp_line
			(start -0.12065 -0.305054)
			(end -0.12065 -0.2794)
			(stroke
				(width 0.1)
				(type default)
			)
			(layer "F.Fab")
		)
		(pad "1" smd circle
			(at -0.40005 0 270)
			(size 0 0)
			(layers "F.Cu" "F.Mask" "F.Paste")
			(net "PVCCIN_CPU0")
		)
		(pad "2" smd circle
			(at 0.40005 0 270)
			(size 0 0)
			(layers "F.Cu" "F.Mask" "F.Paste")
			(net "GND")
		)
	)
	(footprint ""
		(layer "F.Cu")
		(at 299.865034 -409.69184)
		(property "Reference" "R4689"
			(at 0 0 0)
			(layer "F.SilkS")
			(hide yes)
			(effects
				(font
					(size 1.27 1.27)
				)
			)
		)
		(property "Value" ""
			(at 0 0 0)
			(layer "F.Fab")
			(effects
				(font
					(size 1.27 1.27)
				)
			)
		)
		(duplicate_pad_numbers_are_jumpers no)
		(fp_line
			(start -0.7874 -0.4064)
			(end 0.7874 -0.4064)
			(stroke
				(width 0.1524)
				(type default)
			)
			(layer "F.SilkS")
		)
		(fp_line
			(start -0.7874 0.4064)
			(end -0.7874 -0.4064)
			(stroke
				(width 0.1524)
				(type default)
			)
			(layer "F.SilkS")
		)
		(fp_line
			(start 0.7874 -0.4064)
			(end 0.7874 0.4064)
			(stroke
				(width 0.1524)
				(type default)
			)
			(layer "F.SilkS")
		)
		(fp_line
			(start 0.7874 0.4064)
			(end -0.7874 0.4064)
			(stroke
				(width 0.1524)
				(type default)
			)
			(layer "F.SilkS")
		)
		(fp_line
			(start -0.67945 -0.305054)
			(end -0.12065 -0.305054)
			(stroke
				(width 0.1)
				(type default)
			)
			(layer "F.Fab")
		)
		(fp_line
			(start -0.67945 0.3048)
			(end -0.67945 -0.305054)
			(stroke
				(width 0.1)
				(type default)
			)
			(layer "F.Fab")
		)
		(fp_line
			(start -0.12065 -0.305054)
			(end -0.12065 -0.2794)
			(stroke
				(width 0.1)
				(type default)
			)
			(layer "F.Fab")
		)
		(fp_line
			(start -0.12065 -0.2794)
			(end 0.12065 -0.2794)
			(stroke
				(width 0.1)
				(type default)
			)
			(layer "F.Fab")
		)
		(fp_line
			(start -0.12065 0.2794)
			(end -0.12065 0.3048)
			(stroke
				(width 0.1)
				(type default)
			)
			(layer "F.Fab")
		)
		(fp_line
			(start -0.12065 0.3048)
			(end -0.67945 0.3048)
			(stroke
				(width 0.1)
				(type default)
			)
			(layer "F.Fab")
		)
		(fp_line
			(start 0.120396 0.2794)
			(end -0.12065 0.2794)
			(stroke
				(width 0.1)
				(type default)
			)
			(layer "F.Fab")
		)
		(fp_line
			(start 0.120396 0.3048)
			(end 0.120396 0.2794)
			(stroke
				(width 0.1)
				(type default)
			)
			(layer "F.Fab")
		)
		(fp_line
			(start 0.12065 -0.3048)
			(end 0.67945 -0.3048)
			(stroke
				(width 0.1)
				(type default)
			)
			(layer "F.Fab")
		)
		(fp_line
			(start 0.12065 -0.2794)
			(end 0.12065 -0.3048)
			(stroke
				(width 0.1)
				(type default)
			)
			(layer "F.Fab")
		)
		(fp_line
			(start 0.67945 -0.3048)
			(end 0.67945 0.3048)
			(stroke
				(width 0.1)
				(type default)
			)
			(layer "F.Fab")
		)
		(fp_line
			(start 0.67945 0.3048)
			(end 0.120396 0.3048)
			(stroke
				(width 0.1)
				(type default)
			)
			(layer "F.Fab")
		)
		(pad "1" smd circle
			(at -0.40005 0)
			(size 0 0)
			(layers "F.Cu" "F.Mask" "F.Paste")
			(net "SMB_LM75_0_3V3AUX_SCL")
		)
		(pad "2" smd circle
			(at 0.40005 0)
			(size 0 0)
			(layers "F.Cu" "F.Mask" "F.Paste")
			(net "SMB_HSC_TYPE_ADC_SCL")
		)
	)
)
